FILE_TYPE = CONNECTIVITY;
{Allegro Design Entry HDL 17.2-2016 S081 (4005846) 1/11/2022}
"PAGE_NUMBER" = 313;
0"NC";
1"P3V3_AUX\g";
2"P3V3_AUX\g";
3"GND\g";
4"GND\g";
5"NC_FPGA_PR13A"CDS_PHYS_NET_NAME"PWRGD_PCH_PWROK_R";
6"OCP_V3_2_P3V3_ADC_ALERT"CDS_PHYS_NET_NAME"PWRGD_PVCCINFAON_CPU1";
7"FM_UARTSW_LSB_N"CDS_PHYS_NET_NAME"PWRGD_PVCCINFAON_CPU1";
8"OCP_SFF_P3V3_ADC_ALERT"CDS_PHYS_NET_NAME"PWRGD_PVCCFA_EHV_CPU1";
9"P12V_SCM_ADC_ALERT"CDS_PHYS_NET_NAME"PWRGD_PVCCD_HV_CPU1";
10"IRQ_PVCCFA_CPU0_VRHOT_R_N"CDS_PHYS_NET_NAME"PWRGD_SYS_PWROK_R";
11"PWRGD_PCH_PWROK_R"CDS_PHYS_NET_NAME"PWRGD_PCH_PWROK_R";
12"IRQ_PVCCFA_CPU1_VRHOT_R_N"CDS_PHYS_NET_NAME"PWRGD_PCH_PWROK_R";
13"PWRGD_SYS_PWROK_R"CDS_PHYS_NET_NAME"PWRGD_SYS_PWROK_R";
14"PWRGD_P1V8_PCH_AUX_PLD"CDS_PHYS_NET_NAME"PWRGD_P1V8_PCH_AUX_PLD";
15"PWRGD_P1V05_PCH_AUX"CDS_PHYS_NET_NAME"PWRGD_P1V05_PCH_AUX";
16"PWRGD_PS_PWROK_PLD_ISO_R"CDS_PHYS_NET_NAME"PWRGD_PS_PWROK_PLD_R";
17"FM_PFR_DSW_PWROK_N"CDS_PHYS_NET_NAME"FM_PFR_DSW_PWROK_N";
18"PWRGD_PVCCD_HV_CPU1"CDS_PHYS_NET_NAME"PWRGD_PVCCD_HV_CPU1";
19"PWRGD_PVCCFA_EHV_FIVRA_CPU1"CDS_PHYS_NET_NAME"PWRGD_PVCCFA_EHV_FIVRA_CPU1";
20"PWRGD_PVCCINFAON_CPU1"CDS_PHYS_NET_NAME"PWRGD_PVCCINFAON_CPU1";
21"PWRGD_PVCCINFAON_CPU0"CDS_PHYS_NET_NAME"PWRGD_PVCCINFAON_CPU0";
22"PWRGD_PVCCFA_EHV_CPU1"CDS_PHYS_NET_NAME"PWRGD_PVCCFA_EHV_CPU1";
23"E1S_0_P3V3_ADC_ALERT"CDS_PHYS_NET_NAME"PWRGD_PVCCFA_EHV_CPU0";
24"E1S_0_LED_ACT_R_N";
25"FM_SMB_2_ALERT_GPU_ISO_R_N"$PHYS_NET_NAME"RST_PCIE_M2_N"CDS_PHYS_NET_NAME"FM_SMB_2_ALERT_GPU_ISO_R_N";
26"FM_SMB_1_ALERT_GPU_ISO_R_N"$PHYS_NET_NAME"RST_PCIE_M2_N"CDS_PHYS_NET_NAME"FM_SMB_1_ALERT_GPU_ISO_R_N";
27"HP_LVC3_OCP_V3_1_HSC_PWRGD_PLD_R";
28"HP_LVC3_OCP_V3_2_HSC_PWRGD_PLD_R";
29"OCP_V3_2_MAIN_PWR_EN";
30"OCP_SFF_MAIN_PWR_EN";
31"PWRGD_FAIL_CPU1_GH_R"CDS_PHYS_NET_NAME"PWRGD_FAIL_CPU1_AB_R";
32"PWRGD_FAIL_CPU1_EF_R"CDS_PHYS_NET_NAME"PWRGD_FAIL_CPU1_EF_R";
33"PWRGD_FAIL_CPU1_CD_R"CDS_PHYS_NET_NAME"PWRGD_FAIL_CPU1_CD_R";
34"PWRGD_FAIL_CPU1_AB_R"CDS_PHYS_NET_NAME"PWRGD_FAIL_CPU1_GH_R";
35"PWRGD_FAIL_CPU0_GH_R"CDS_PHYS_NET_NAME"PWRGD_FAIL_CPU0_EF_R";
36"PWRGD_FAIL_CPU0_EF_R"CDS_PHYS_NET_NAME"PWRGD_FAIL_CPU0_AB_R";
37"PWRGD_FAIL_CPU0_CD_R"CDS_PHYS_NET_NAME"PWRGD_FAIL_CPU0_CD_R";
38"PWRGD_FAIL_CPU0_AB_R"CDS_PHYS_NET_NAME"PWRGD_FAIL_CPU0_GH_R";
39"FM_PS_EN_PLD_R"CDS_PHYS_NET_NAME"FM_PS_EN_PLD_R";
40"FM_SLPS4_PLD_N"CDS_PHYS_NET_NAME"FM_SLPS4_PLD_N";
41"FM_JTAG_BMC_MUX_SEL_R"CDS_PHYS_NET_NAME"FM_JTAG_BMC_MUX_SEL_R";
42"FM_RST_PERST_BIT1"CDS_PHYS_NET_NAME"FM_RST_PERST_BIT1";
43"FM_RST_PERST_BIT0"CDS_PHYS_NET_NAME"FM_RST_PERST_BIT0";
44"FM_CPU_RMCA_CATERR_DLY_LVT3_R_N"CDS_PHYS_NET_NAME"FM_CPU_RMCA_CATERR_DLY_LVT3_R_N";
45"M2_0_P3V3_ADC_ALERT"CDS_PHYS_NET_NAME"PWRGD_PVCCFA_EHV_FIVRA_CPU1";
46"NC_FPGA_PR14A"CDS_PHYS_NET_NAME"PWRGD_PVCCFA_EHV_FIVRA_CPU1";
47"NC_FPGA_PR14B"CDS_PHYS_NET_NAME"PWRGD_PVCCD_HV_CPU1";
48"IRQ_PVCCIN_CPU1_VRHOT_R_N"CDS_PHYS_NET_NAME"IRQ_CPU1_VRHOT_N";
49"IRQ_PVCCIN_CPU0_VRHOT_R_N"CDS_PHYS_NET_NAME"IRQ_CPU0_VRHOT_N";
50"PWRGD_PVCCFA_EHV_CPU0"CDS_PHYS_NET_NAME"PWRGD_PVCCFA_EHV_CPU0";
51"PWRGD_PVCCIN_CPU1"CDS_PHYS_NET_NAME"PWRGD_PVCCIN_CPU1";
52"PWRGD_DSW_PWROK_R3"CDS_PHYS_NET_NAME"PWRGD_DSW_PWROK_R3";
53"FM_CPU1_PKGID2"CDS_PHYS_NET_NAME"FM_CPU1_PKGID2";
54"FM_CPU1_PKGID1"CDS_PHYS_NET_NAME"FM_CPU1_PKGID1";
55"FM_CPU1_PKGID0"CDS_PHYS_NET_NAME"FM_CPU1_PKGID0";
56"FM_UARTSW_MSB_N"CDS_PHYS_NET_NAME"PWRGD_PVCCFA_EHV_FIVRA_CPU1";
57"FM_SOL_UART_CH_SEL"CDS_PHYS_NET_NAME"PWRGD_PVCCD_HV_CPU1";
58"FM_THERMAL_ALERT_R_N";
59"NC_FPGA_PR16C"CDS_PHYS_NET_NAME"PWRGD_SYS_PWROK_R";
60"NC_FPGA_PR16D"CDS_PHYS_NET_NAME"PWRGD_PCH_PWROK_R";
61"HP_LVC3_OCP_V3_1_P12V_PWRGD"CDS_PHYS_NET_NAME"IRQ_PCH_SCI_WHEA_R_N";
62"NC_FPGA_PR30D"CDS_PHYS_NET_NAME"NC_FPGA_PR16D";
63"RST_PERST_SWB_N"CDS_PHYS_NET_NAME"PWRGD_PCH_PWROK_R";
64"FM_PCH_SPKR_R"CDS_PHYS_NET_NAME"GPU_FPGA_RST_R_N";
65"FM_JTAG_TCK_MUX_SEL_R"CDS_PHYS_NET_NAME"GPU_FPGA_RST_N";
66"FM_BMC_CPU_FBRK_OUT_R_N"CDS_PHYS_NET_NAME"GPU_FPGA_RST_N";
67"CLK_GEN2_GPU_FPGA_OE_R_N"CDS_PHYS_NET_NAME"GPU_FPGA_RST_N";
68"LED_HDD_ACTIVITY_B_PLD_N"CDS_PHYS_NET_NAME"FM_SMB_1_ALERT_GPU_ISO_R_N";
69"GPU_FPGA_RST_N"CDS_PHYS_NET_NAME"GPU_FPGA_RST_N";
70"FM_CPU1_PROC_ID1"CDS_PHYS_NET_NAME"FM_CPU1_PROC_ID1";
71"FM_CPU1_PROC_ID0"CDS_PHYS_NET_NAME"FM_CPU1_PROC_ID0";
72"FM_CPU0_PROC_ID1"CDS_PHYS_NET_NAME"FM_CPU0_PROC_ID1";
73"FM_CPU0_PKGID0"CDS_PHYS_NET_NAME"FM_CPU0_PKGID0";
74"FM_CPU0_PKGID1"CDS_PHYS_NET_NAME"FM_CPU0_PKGID1";
75"RST_PCIE_CPU1_DEV_PERST_N"CDS_PHYS_NET_NAME"RST_PCIE_CPU1_DEV_PERST_N";
76"FM_CPU0_PKGID2"CDS_PHYS_NET_NAME"FM_CPU0_PKGID2";
77"FM_CPU0_PROC_ID0"CDS_PHYS_NET_NAME"FM_CPU0_PROC_ID0";
78"FM_CPU1_SKTOCC_LVT3_PLD_N"CDS_PHYS_NET_NAME"FM_CPU1_SKTOCC_LVT3_PLD_N";
79"FM_CPU0_SKTOCC_LVT3_PLD_N"CDS_PHYS_NET_NAME"FM_CPU0_SKTOCC_LVT3_PLD_N";
80"HP_LVC3_OCP_V3_2_P12V_PWRGD"CDS_PHYS_NET_NAME"FM_ADR_ACK_R";
81"HP_LVC3_OCP_V3_2_HSC_PWRGD_PLD_R"CDS_PHYS_NET_NAME"FM_ADR_ACK";
82"PWRGD_DSW_PWROK"CDS_PHYS_NET_NAME"PWRGD_DSW_PWROK";
83"FM_PVCCD_HV_CPU1_EN"CDS_PHYS_NET_NAME"FM_PVCCD_HV_CPU1_EN";
84"FM_PVCCINFAON_CPU0_R_EN"CDS_PHYS_NET_NAME"FM_PVCCINFAON_CPU0_R_EN";
85"PWRGD_DSW_PWROK_R3"CDS_PHYS_NET_NAME"VOL_SEN_ALERT_R";
86"FM_ESPI_PLD_R1_EN"CDS_PHYS_NET_NAME"FM_ESPI_PLD_R1_EN";
87"PWRGD_PS_PWROK_PLD"CDS_PHYS_NET_NAME"PWRGD_PS_PWROK_PLD";
88"PWRGD_PS_PWROK";
89"MB0_P12V_STBY_PWRGD"CDS_PHYS_NET_NAME"MB0_P12V_STBY_PWRGD";
90"FM_PCH_SPKR_R"CDS_PHYS_NET_NAME"GPU_FPGA_RST_R_N";
91"CLK_25M_OSC_MAIN_FPGA"CDS_PHYS_NET_NAME"CLK_25M_OSC_MAIN_FPGA";
92"FM_JTAG_TCK_MUX_SEL_R"CDS_PHYS_NET_NAME"GPU_FPGA_RST_N";
93"FM_SMB_2_ALERT_GPU_ISO_N"CDS_PHYS_NET_NAME"FM_SMB_2_ALERT_GPU_ISO_N";
94"LED_HDD_ACTIVITY_B_PLD_N"CDS_PHYS_NET_NAME"FM_SMB_1_ALERT_GPU_ISO_R_N";
95"GPU_FPGA_RST_R_N"CDS_PHYS_NET_NAME"GPU_FPGA_RST_R_N";
96"E1S_0_LED_ACT_N"CDS_PHYS_NET_NAME"FM_SMB_2_ALERT_GPU_ISO_R_N";
97"E1S_0_LED_ACT_R_N"CDS_PHYS_NET_NAME"FM_SMB_2_ALERT_GPU_ISO_N";
98"FM_JTAG_TCK_MUX_SEL"CDS_PHYS_NET_NAME"GPU_FPGA_RST_R_N";
99"CLK_GEN2_GPU_FPGA_OE_N"CDS_PHYS_NET_NAME"GPU_FPGA_RST_R_N";
100"FM_BMC_CPU_FBRK_OUT_N"CDS_PHYS_NET_NAME"GPU_FPGA_RST_R_N";
101"FM_PVCCFA_EHV_FIVRA_CPU1_R_EN"CDS_PHYS_NET_NAME"FM_PVCCFA_EHV_FIVRA_CPU1_R_EN";
102"FM_SMB_2_ALERT_GPU_ISO_R_N"CDS_PHYS_NET_NAME"FM_SMB_2_ALERT_GPU_ISO_R_N";
103"FM_SMB_1_ALERT_GPU_ISO_R_N"CDS_PHYS_NET_NAME"FM_SMB_1_ALERT_GPU_ISO_R_N";
104"FM_BMC_CPU_FBRK_OUT_R_N"CDS_PHYS_NET_NAME"GPU_FPGA_RST_N";
105"CLK_GEN2_GPU_FPGA_OE_R_N"CDS_PHYS_NET_NAME"GPU_FPGA_RST_N";
106"FM_PCH_SPKR"CDS_PHYS_NET_NAME"GPU_FPGA_RST_N";
107"GPU_FPGA_RST_N"CDS_PHYS_NET_NAME"GPU_FPGA_RST_N";
108"PU_CLK25M_OSC_FPGA_EN"CDS_PHYS_NET_NAME"PU_CLK25M_OSC_FPGA_EN";
109"CLK_25M_OSC_FPGA_R"CDS_PHYS_NET_NAME"CLK_25M_OSC_FPGA_R";
110"FM_ESPI_PLD_R_EN"CDS_PHYS_NET_NAME"VOL_SEN_ALERT";
111"FM_JTAG_BMC_MUX_SEL_R";
112"FM_THERMAL_ALERT_R_N";
113"FM_JTAG_BMC_MUX_SEL_FROM_BMC_R";
114"FM_JTAG_BMC_MUX_SEL"CDS_PHYS_NET_NAME"FM_JTAG_BMC_MUX_SEL";
115"LED_HDD_ACTIVITY_B_N"CDS_PHYS_NET_NAME"FM_SMB_1_ALERT_GPU_ISO_N";
116"FM_SMB_1_ALERT_GPU_ISO_N"CDS_PHYS_NET_NAME"FM_SMB_1_ALERT_GPU_ISO_N";
117"HP_LVC3_OCP_V3_1_HSC_PWRGD_PLD_R"CDS_PHYS_NET_NAME"IRQ_PCH_SCI_WHEA_N";
118"FM_PVPP_HBM_CPU0_EN"CDS_PHYS_NET_NAME"FM_PVPP_HBM_CPU0_EN";
119"FM_P1V05_PCH_AUX_EN"CDS_PHYS_NET_NAME"FM_P1V05_PCH_AUX_EN";
120"FM_THERMAL_ALERT_N";
121"FM_ESPI_PLD_R_EN"CDS_PHYS_NET_NAME"FM_ESPI_PLD_R_EN";
122"FM_P5V_EN"CDS_PHYS_NET_NAME"FM_P5V_EN";
123"FM_PCH_P1V8_AUX_EN"CDS_PHYS_NET_NAME"FM_PCH_P1V8_AUX_EN";
124"FM_AUX_SW_EN"CDS_PHYS_NET_NAME"FM_AUX_SW_EN";
125"FM_PVCCIN_CPU1_R_EN"CDS_PHYS_NET_NAME"FM_PVCCIN_CPU1_R_EN";
126"FM_PVCCIN_CPU0_R_EN"CDS_PHYS_NET_NAME"FM_PVCCIN_CPU0_R_EN";
127"FM_PVNN_MAIN_CPU1_EN"CDS_PHYS_NET_NAME"FM_PVNN_MAIN_CPU1_EN";
128"FM_PVPP_HBM_CPU1_EN"CDS_PHYS_NET_NAME"FM_PVPP_HBM_CPU1_EN";
129"SMB_2_PLD_3V3AUX_SCL_R1"CDS_PHYS_NET_NAME"SMB_2_PLD_3V3AUX_SCL";
130"SMB_2_PLD_3V3AUX_SDA_R1"CDS_PHYS_NET_NAME"SMB_2_PLD_3V3AUX_SDA";
131"RST_PCIE_CPU0_DEV_PERST_N"CDS_PHYS_NET_NAME"RST_PCIE_CPU0_DEV_PERST_N";
132"FM_PVCCFA_EHV_FIVRA_CPU0_R_EN"CDS_PHYS_NET_NAME"FM_PVCCFA_EHV_FIVRA_CPU0_R_EN";
133"FM_PVCCFA_EHV_CPU1_R_EN"CDS_PHYS_NET_NAME"FM_PVCCFA_EHV_CPU1_R_EN";
134"FM_PVCCFA_EHV_CPU0_R_EN"CDS_PHYS_NET_NAME"FM_PVCCFA_EHV_CPU0_R_EN";
135"FM_PVCCD_HV_CPU0_EN"CDS_PHYS_NET_NAME"FM_PVCCD_HV_CPU0_EN";
136"FM_PVCCINFAON_CPU1_R_EN"CDS_PHYS_NET_NAME"FM_PVCCINFAON_CPU1_R_EN";
137"FM_PVNN_MAIN_CPU0_EN"CDS_PHYS_NET_NAME"FM_PVNN_MAIN_CPU0_EN";
%"LCMXO3LF9400C5BG484C"
"7","(575,500)","0","pure_quanta","I1";
;
PART_NUMBER"AJ094000T08"
PART_TYPE"SMLF"
VALUE"LCMXO3LF-9400C-5BG484C"
MATERIAL"IC"
$LOCATION"U249"
CDS_LIB"pure_quanta"
NEEDS_NO_SIZE"TRUE"
CDS_LMAN_SYM_OUTLINE"-475,1275,475,-1275"
CDS_LOCATION"U249"
$SEC"7"
CDS_SEC"7";
"PR30D"
$PN"Y20"62;
"PR30C"
$PN"W19"63;
"PR28D"
$PN"U18"24;
"PR28C"
$PN"U19"25;
"PR28B"
$PN"W21"26;
"PR28A"
$PN"Y22"27;
"PR27D"
$PN"U20"28;
"PR27C"
$PN"T17"29;
"PR27B"
$PN"T18"30;
"PR27A"
$PN"T19"31;
"PR26D"
$PN"T20"32;
"PR26C"
$PN"R16"33;
"PR26B"
$PN"R17"34;
"PR26A"
$PN"R18"35;
"PR25D"
$PN"R19"36;
"PR25C"
$PN"R20"37;
"PR24D"
$PN"U21"40;
"PR24C"
$PN"U22"41;
"PR24B"
$PN"P16"44;
"PR24A"
$PN"P17"42;
"PR21D"
$PN"P18"43;
"PR21C"
$PN"P19"48;
"PR21B"
$PN"T21"49;
"PR21A"
$PN"T22"52;
"PR20D"
$PN"P20"53;
"PR20C"
$PN"P22"54;
"PR19D"
$PN"N19"74;
"PR19C"
$PN"N20"73;
"PR18D"
$PN"N18"72;
"PR18C"
$PN"N17"77;
"PR18B"
$PN"N16"78;
"PR18A"
$PN"M16"79;
"PR17D"
$PN"M19"75;
"PR17C"
$PN"M20"131;
"PR16D"
$PN"M17"60;
"PR16C"
$PN"L22"59;
"PR14D"
$PN"L20"56;
"PR14C"
$PN"L19"7;
"PR13D"
$PN"K16"9;
"PR13C"
$PN"K17"45;
"PR13B"
$PN"K18"6;
"PR13A"
$PN"K19"5;
"PR12D"
$PN"K20"8;
"PR12C"
$PN"J20"23;
"PR12B"
$PN"J22"12;
"PR12A"
$PN"J21"10;
"PR11D"
$PN"J19"11;
"PR11C"
$PN"J18"13;
"PR11B"
$PN"J17"14;
"PR11A"
$PN"J16"15;
"PR10D"
$PN"H16"16;
"PR10C"
$PN"H17"17;
"PR10B"
$PN"H18"18;
"PR10A"
$PN"H19"19;
"PR7D"
$PN"H20"20;
"PR7C"
$PN"G17"21;
"PR6D"
$PN"G18"51;
"PR6C"
$PN"G19"121;
"PR6B"
$PN"G20"119;
"PR6A"
$PN"G21"122;
"PR5D"
$PN"F19"123;
"PR5C"
$PN"F18"124;
"PR5B"
$PN"G22"118;
"PR5A"
$PN"F22"128;
"PR4B"
$PN"E21"127;
"PR4A"
$PN"E22"137;
"PR4D"
$PN"E20"125;
"PR4C"
$PN"E19"126;
"PR3D"
$PN"D20"136;
"PR3C"
$PN"D19"84;
"PR2D"
$PN"G16"133;
"PR2C"
$PN"F17"134;
"PR2A||R_GPLLT_FB"
$PN"C21"135;
"PR2B||R_GPLLC_FB"
$PN"C22"83;
"PR3A||R_GPLLT_IN"
$PN"D22"132;
"PR3B||R_GPLLC_IN"
$PN"D21"101;
"PR7A"
$PN"H22"50;
"PR7B"
$PN"H21"22;
"PR14A"
$PN"L17"46;
"PR14B"
$PN"L16"47;
"PR16A"
$PN"K22"57;
"PR16B"
$PN"L21"58;
"PR17A||PCLKT1_0"
$PN"M22"129;
"PR17B||PCLKC1_0"
$PN"M21"130;
"PR19A"
$PN"N22"71;
"PR19B"
$PN"P21"70;
"PR20A"
$PN"R22"76;
"PR20B"
$PN"R21"55;
"PR25A"
$PN"V22"39;
"PR25B"
$PN"W22"38;
"PR29A"
$PN"AA22"68;
"PR29C"
$PN"U17"65;
"PR29B"
$PN"Y21"69;
"PR29D"
$PN"V19"67;
"PR30A"
$PN"V18"66;
"PR30B"
$PN"W20"64;
%"Q_RES"
"1","(-950,-3025)","0","pure_quanta","I115";
;
PART_NUMBER"CS03322FB03"
WATTAGE"1/16W"
PACK_TYPE"0402LF"
VALUE"33.2"
TOLERANCE"1%"
MATERIAL"CHIP"
$LOCATION"R1100"
CDS_LIB"pure_quanta"
CDS_LOCATION"R1100"
$SEC"1"
CDS_SEC"1";
"B"
$PN"2"91;
"A"
$PN"1"109;
%"UNIVERSAL_GND"
"1","(-2000,-3275)","0","logical_power","I123";
;
CDS_LIB"logical_power"
HDL_POWER"GND";
"A"4;
%"UNIVERSAL_POWER"
"1","(-3000,-2450)","0","logical_power","I124";
;
HDL_POWER"P3V3_AUX"
CDS_LIB"logical_power";
"A"2;
%"UNIVERSAL_GND"
"1","(-3000,-3000)","0","logical_power","I125";
;
CDS_LIB"logical_power"
HDL_POWER"GND";
"A"3;
%"Q_CAP"
"1","(-3000,-2775)","2","pure_quanta","I126";
;
PART_NUMBER"CH4104K1B00"
VALUE"0.1UF"
VOLTAGE"25V"
MATERIAL"X7R"
TOLERANCE"10%"
PACK_TYPE"0402"
$LOCATION"C1320"
CDS_LIB"pure_quanta"
CDS_LOCATION"C1320"
$SEC"1"
CDS_SEC"1";
"B"
$PN"2"3;
"A"
$PN"1"2;
%"Q_OSC4P"
"1","(-2450,-3100)","0","pure_quanta","I127";
;
PART_NUMBER"BF625000014"
MATERIAL"OSC"
VALUE"25MHZ"
PACK_TYPE"SMLF"
$LOCATION"OSC2"
NEEDS_NO_SIZE"TRUE"
CDS_LIB"pure_quanta"
CDS_LOCATION"OSC2"
$SEC"1"
CDS_SEC"1";
"VDD"
$PN"4"2;
"OUT"
$PN"3"109;
"GND"
$PN"2"4;
"OE"
$PN"1"108;
%"UNIVERSAL_POWER"
"1","(-3725,-2725)","0","logical_power","I128";
;
HDL_POWER"P3V3_AUX"
CDS_LIB"logical_power";
"A"1;
%"Q_RES"
"2","(-3725,-2950)","2","pure_quanta","I129";
;
PART_NUMBER"CS31002FB08"
VALUE"10K"
TOLERANCE"1%"
WATTAGE"1/16W"
MATERIAL"CHIP"
PACK_TYPE"0402LF"
$LOCATION"R1099"
CDS_LIB"pure_quanta"
CDS_LOCATION"R1099"
$SEC"1"
CDS_SEC"1";
"A"
$PN"1"1;
"B"
$PN"2"108;
%"Q_RES"
"1","(2675,-2650)","0","pure_quanta","I147";
;
PART_NUMBER"CS03322FB03"
VALUE"33.2"
TOLERANCE"1%"
MATERIAL"CHIP"
WATTAGE"1/16W"
PACK_TYPE"0402LF"
$LOCATION"R4259"
CDS_LIB"pure_quanta"
CDS_LOCATION"R4259"
$SEC"1"
CDS_SEC"1";
"B"
$PN"2"112;
"A"
$PN"1"120;
%"Q_RES"
"1","(2700,-1000)","0","pure_quanta","I159";
;
PART_NUMBER"CS00002JB13"
TOLERANCE"5%"
VALUE"0"
MATERIAL"CHIP"
PACK_TYPE"0402LF"
WATTAGE"1/16W"
$LOCATION"R4599"
CDS_LIB"pure_quanta"
CDS_LOCATION"R4599"
$SEC"1"
CDS_SEC"1";
"B"
$PN"2"81;
"A"
$PN"1"80;
%"Q_RES"
"1","(2700,-1175)","0","pure_quanta","I160";
;
PART_NUMBER"CS00002JB13"
TOLERANCE"5%"
VALUE"0"
MATERIAL"CHIP"
WATTAGE"1/16W"
PACK_TYPE"0402LF"
$LOCATION"R4600"
CDS_LIB"pure_quanta"
CDS_LOCATION"R4600"
$SEC"1"
CDS_SEC"1";
"B"
$PN"2"117;
"A"
$PN"1"61;
%"Q_RES"
"1","(2675,-2950)","0","pure_quanta","I166";
;
PART_NUMBER"CS00002JB13"
VALUE"0"
TOLERANCE"5%"
MATERIAL"CHIP"
$LOCATION"R4088"
WATTAGE"1/16W"
PACK_TYPE"0402LF"
CDS_LIB"pure_quanta"
CDS_LOCATION"R4088"
$SEC"1"
CDS_SEC"1";
"B"
$PN"2"114;
"A"
$PN"1"113;
%"Q_RES"
"1","(2675,-2850)","0","pure_quanta","I167";
;
PART_NUMBER"CS00002JB13"
VALUE"0"
TOLERANCE"5%"
MATERIAL"EMPTY"
$LOCATION"R1833"
CDS_LIB"pure_quanta"
WATTAGE"1/16W"
PACK_TYPE"0402LF"
CDS_LOCATION"R1833"
$SEC"1"
CDS_SEC"1";
"B"
$PN"2"114;
"A"
$PN"1"111;
%"Q_RES"
"1","(-1025,-1000)","0","pure_quanta","I175";
;
PART_NUMBER"CS00002JB13"
TOLERANCE"5%"
VALUE"0"
MATERIAL"CHIP"
$LOCATION"R3066"
WATTAGE"1/16W"
PACK_TYPE"0402LF"
CDS_LIB"pure_quanta"
CDS_LOCATION"R3066"
$SEC"1"
CDS_SEC"1";
"B"
$PN"2"103;
"A"
$PN"1"116;
%"Q_RES"
"1","(-1025,-1200)","0","pure_quanta","I176";
;
PART_NUMBER"CS00002JB13"
MATERIAL"CHIP"
TOLERANCE"5%"
VALUE"0"
$LOCATION"R3067"
WATTAGE"1/16W"
PACK_TYPE"0402LF"
CDS_LIB"pure_quanta"
CDS_LOCATION"R3067"
$SEC"1"
CDS_SEC"1";
"B"
$PN"2"102;
"A"
$PN"1"93;
%"Q_RES"
"1","(-1025,-1425)","0","pure_quanta","I180";
;
PART_NUMBER"CS00002JB13"
TOLERANCE"5%"
MATERIAL"CHIP"
$LOCATION"R4606"
VALUE"0"
CDS_LIB"pure_quanta"
PACK_TYPE"0402LF"
WATTAGE"1/16W"
CDS_LOCATION"R4606"
$SEC"1"
CDS_SEC"1";
"B"
$PN"2"96;
"A"
$PN"1"97;
%"Q_RES"
"1","(-1025,-1625)","0","pure_quanta","I183";
;
PART_NUMBER"CS00002JB13"
MATERIAL"CHIP"
TOLERANCE"5%"
VALUE"0"
$LOCATION"R4607"
CDS_LIB"pure_quanta"
PACK_TYPE"0402LF"
WATTAGE"1/16W"
CDS_LOCATION"R4607"
$SEC"1"
CDS_SEC"1";
"B"
$PN"2"94;
"A"
$PN"1"115;
%"Q_RES"
"1","(-1050,-1900)","0","pure_quanta","I190";
;
PART_NUMBER"CS03322FB03"
VALUE"33.2"
WATTAGE"1/16W"
TOLERANCE"1%"
MATERIAL"CHIP"
PACK_TYPE"0402LF"
$LOCATION"R4608"
CDS_LIB"pure_quanta"
CDS_LOCATION"R4608"
$SEC"1"
CDS_SEC"1";
"B"
$PN"2"95;
"A"
$PN"1"107;
%"Q_RES"
"1","(-1050,-2125)","0","pure_quanta","I194";
;
PART_NUMBER"CS03322FB03"
MATERIAL"CHIP"
VALUE"33.2"
$LOCATION"R4609"
WATTAGE"1/16W"
PACK_TYPE"0402LF"
TOLERANCE"1%"
CDS_LIB"pure_quanta"
CDS_LOCATION"R4609"
$SEC"1"
CDS_SEC"1";
"B"
$PN"2"98;
"A"
$PN"1"92;
%"Q_RES"
"1","(-1050,-2350)","0","pure_quanta","I200";
;
PART_NUMBER"CS03322FB03"
VALUE"33.2"
MATERIAL"CHIP"
$LOCATION"R4610"
WATTAGE"1/16W"
PACK_TYPE"0402LF"
TOLERANCE"1%"
CDS_LIB"pure_quanta"
CDS_LOCATION"R4610"
$SEC"1"
CDS_SEC"1";
"B"
$PN"2"99;
"A"
$PN"1"105;
%"Q_RES"
"1","(-1050,-2525)","0","pure_quanta","I206";
;
PART_NUMBER"CS03322FB03"
VALUE"33.2"
MATERIAL"CHIP"
$LOCATION"R4611"
CDS_LIB"pure_quanta"
TOLERANCE"1%"
PACK_TYPE"0402LF"
WATTAGE"1/16W"
CDS_LOCATION"R4611"
$SEC"1"
CDS_SEC"1";
"B"
$PN"2"100;
"A"
$PN"1"104;
%"Q_RES"
"1","(-1050,-2675)","0","pure_quanta","I211";
;
PART_NUMBER"CS03322FB03"
VALUE"33.2"
MATERIAL"CHIP"
$LOCATION"R4612"
WATTAGE"1/16W"
PACK_TYPE"0402LF"
TOLERANCE"1%"
CDS_LIB"pure_quanta"
CDS_LOCATION"R4612"
$SEC"1"
CDS_SEC"1";
"B"
$PN"2"90;
"A"
$PN"1"106;
%"Q_RES"
"1","(2675,-1400)","0","pure_quanta","I83";
;
PART_NUMBER"CS00002JB13"
MATERIAL"CHIP"
TOLERANCE"5%"
VALUE"0"
$LOCATION"R2412"
WATTAGE"1/16W"
PACK_TYPE"0402LF"
CDS_LIB"pure_quanta"
CDS_LOCATION"R2412"
$SEC"1"
CDS_SEC"1";
"B"
$PN"2"85;
"A"
$PN"1"82;
%"Q_RES"
"1","(2675,-1600)","0","pure_quanta","I84";
;
PART_NUMBER"CS00002JB13"
TOLERANCE"5%"
MATERIAL"CHIP"
VALUE"0"
$LOCATION"R2452"
WATTAGE"1/16W"
PACK_TYPE"0402LF"
CDS_LIB"pure_quanta"
CDS_LOCATION"R2452"
$SEC"1"
CDS_SEC"1";
"B"
$PN"2"86;
"A"
$PN"1"110;
%"Q_RES"
"1","(2650,-1800)","0","pure_quanta","I85";
;
PART_NUMBER"CS00002JB13"
MATERIAL"CHIP"
TOLERANCE"5%"
VALUE"0"
$LOCATION"R3047"
WATTAGE"1/16W"
PACK_TYPE"0402LF"
CDS_LIB"pure_quanta"
CDS_LOCATION"R3047"
$SEC"1"
CDS_SEC"1";
"B"
$PN"2"87;
"A"
$PN"1"89;
%"Q_RES"
"1","(2650,-1975)","0","pure_quanta","I86";
;
PART_NUMBER"CS00002JB13"
VALUE"0"
TOLERANCE"5%"
MATERIAL"CHIP"
$LOCATION"R3048"
CDS_LIB"pure_quanta"
PACK_TYPE"0402LF"
WATTAGE"1/16W"
CDS_LOCATION"R3048"
$SEC"1"
CDS_SEC"1";
"B"
$PN"2"88;
"A"
$PN"1"89;
END.
